FILE_TYPE = CONNECTIVITY;
{Allegro Design Entry HDL 16.5-S008 (v16-5-13Y) 10/18/2011}
"PAGE_NUMBER" = 1;
0"NC";
1"P5V_STBY \G";
2"G\I";
%"SYNONYM"
"1","(1850,2050)","0","mstr_standard","4P";
;
NEEDS_NO_SIZE"TRUE"
BODY_TYPE"PLUMBING"
CDS_LIB"mstr_standard";
"A\NWC\NAC"2;
"A\NWC\NAC"1;
%"DRAWING"
"2","(1275,1750)","0","mstr_standard","";
;
LAST_MODIFIED"Tue Oct 25 14:31:39 2011"
TITLE"P5V_STBY"
ABBREV"P5V_STBY";
END.
